(kicad_pcb
	(version 20260206)
	(generator "pcbnew")
	(generator_version "10.0")
	(general
		(thickness 1.6)
		(legacy_teardrops no)
	)
	(paper "A4")
	(title_block
		(title "03242023_DA0F0TMBIJ0_F0T_Motherboard_J_brd_V01_OCP.brd")
		(comment 1 "Grand Teton / footprints 3647-3652 of 6105")
	)
	(layers
		(0 "F.Cu" signal "TOP")
		(4 "In1.Cu" signal "GND")
		(6 "In2.Cu" signal "IN1")
		(8 "In3.Cu" signal "GND1")
		(10 "In4.Cu" signal "IN2")
		(12 "In5.Cu" signal "GND2")
		(14 "In6.Cu" signal "IN3")
		(16 "In7.Cu" signal "GND3")
		(18 "In8.Cu" signal "VCC")
		(20 "In9.Cu" signal "VCC1")
		(22 "In10.Cu" signal "GND4")
		(24 "In11.Cu" signal "IN4")
		(26 "In12.Cu" signal "GND5")
		(28 "In13.Cu" signal "IN5")
		(30 "In14.Cu" signal "GND6")
		(32 "In15.Cu" signal "IN6")
		(34 "In16.Cu" signal "GND7")
		(2 "B.Cu" signal "BOTTOM")
		(9 "F.Adhes" user "F.Adhesive")
		(11 "B.Adhes" user "B.Adhesive")
		(13 "F.Paste" user "Package Geometry/Pastemask Top")
		(15 "B.Paste" user "Package Geometry/Pastemask Bottom")
		(5 "F.SilkS" user "Ref Des/Silkscreen Top")
		(7 "B.SilkS" user "Ref Des/Silkscreen Bottom")
		(1 "F.Mask" user "Board Geometry/Soldermask Top")
		(3 "B.Mask" user "Board Geometry/Soldermask Bottom")
		(17 "Dwgs.User" user "User.Drawings")
		(19 "Cmts.User" user "User.Comments")
		(21 "Eco1.User" user "User.Eco1")
		(23 "Eco2.User" user "User.Eco2")
		(25 "Edge.Cuts" user "Board Geometry/Outline")
		(27 "Margin" user)
		(31 "F.CrtYd" user "Package Geometry/Place Bound Top")
		(29 "B.CrtYd" user "Package Geometry/Place Bound Bottom")
		(35 "F.Fab" user "Ref Des/Assembly Top")
		(33 "B.Fab" user "Ref Des/Assembly Bottom")
	)
	(footprint ""
		(layer "F.Cu")
		(at 109.580934 -392.12774)
		(property "Reference" "R3460"
			(at 0 0 0)
			(layer "F.SilkS")
			(hide yes)
			(effects
				(font
					(size 1.27 1.27)
				)
			)
		)
		(property "Value" ""
			(at 0 0 0)
			(layer "F.Fab")
			(effects
				(font
					(size 1.27 1.27)
				)
			)
		)
		(duplicate_pad_numbers_are_jumpers no)
		(fp_line
			(start -0.7874 -0.4064)
			(end 0.7874 -0.4064)
			(stroke
				(width 0.1524)
				(type default)
			)
			(layer "F.SilkS")
		)
		(fp_line
			(start -0.7874 0.4064)
			(end -0.7874 -0.4064)
			(stroke
				(width 0.1524)
				(type default)
			)
			(layer "F.SilkS")
		)
		(fp_line
			(start 0.7874 -0.4064)
			(end 0.7874 0.4064)
			(stroke
				(width 0.1524)
				(type default)
			)
			(layer "F.SilkS")
		)
		(fp_line
			(start 0.7874 0.4064)
			(end -0.7874 0.4064)
			(stroke
				(width 0.1524)
				(type default)
			)
			(layer "F.SilkS")
		)
		(fp_line
			(start -0.67945 -0.305054)
			(end -0.12065 -0.305054)
			(stroke
				(width 0.1)
				(type default)
			)
			(layer "F.Fab")
		)
		(fp_line
			(start -0.67945 0.3048)
			(end -0.67945 -0.305054)
			(stroke
				(width 0.1)
				(type default)
			)
			(layer "F.Fab")
		)
		(fp_line
			(start -0.12065 -0.305054)
			(end -0.12065 -0.2794)
			(stroke
				(width 0.1)
				(type default)
			)
			(layer "F.Fab")
		)
		(fp_line
			(start -0.12065 -0.2794)
			(end 0.12065 -0.2794)
			(stroke
				(width 0.1)
				(type default)
			)
			(layer "F.Fab")
		)
		(fp_line
			(start -0.12065 0.2794)
			(end -0.12065 0.3048)
			(stroke
				(width 0.1)
				(type default)
			)
			(layer "F.Fab")
		)
		(fp_line
			(start -0.12065 0.3048)
			(end -0.67945 0.3048)
			(stroke
				(width 0.1)
				(type default)
			)
			(layer "F.Fab")
		)
		(fp_line
			(start 0.120396 0.2794)
			(end -0.12065 0.2794)
			(stroke
				(width 0.1)
				(type default)
			)
			(layer "F.Fab")
		)
		(fp_line
			(start 0.120396 0.3048)
			(end 0.120396 0.2794)
			(stroke
				(width 0.1)
				(type default)
			)
			(layer "F.Fab")
		)
		(fp_line
			(start 0.12065 -0.3048)
			(end 0.67945 -0.3048)
			(stroke
				(width 0.1)
				(type default)
			)
			(layer "F.Fab")
		)
		(fp_line
			(start 0.12065 -0.2794)
			(end 0.12065 -0.3048)
			(stroke
				(width 0.1)
				(type default)
			)
			(layer "F.Fab")
		)
		(fp_line
			(start 0.67945 -0.3048)
			(end 0.67945 0.3048)
			(stroke
				(width 0.1)
				(type default)
			)
			(layer "F.Fab")
		)
		(fp_line
			(start 0.67945 0.3048)
			(end 0.120396 0.3048)
			(stroke
				(width 0.1)
				(type default)
			)
			(layer "F.Fab")
		)
		(pad "1" smd circle
			(at -0.40005 0)
			(size 0 0)
			(layers "F.Cu" "F.Mask" "F.Paste")
			(net "GPU_NVS_PWR_BRAKE_N")
		)
		(pad "2" smd circle
			(at 0.40005 0)
			(size 0 0)
			(layers "F.Cu" "F.Mask" "F.Paste")
			(net "GND")
		)
	)
	(footprint ""
		(layer "F.Cu")
		(at 21.456396 -386.484876 -90)
		(property "Reference" "R3291"
			(at 0 0 270)
			(layer "F.SilkS")
			(hide yes)
			(effects
				(font
					(size 1.27 1.27)
				)
			)
		)
		(property "Value" ""
			(at 0 0 270)
			(layer "F.Fab")
			(effects
				(font
					(size 1.27 1.27)
				)
			)
		)
		(duplicate_pad_numbers_are_jumpers no)
		(fp_line
			(start -0.7874 0.4064)
			(end -0.7874 -0.4064)
			(stroke
				(width 0.1524)
				(type default)
			)
			(layer "F.SilkS")
		)
		(fp_line
			(start 0.7874 0.4064)
			(end -0.7874 0.4064)
			(stroke
				(width 0.1524)
				(type default)
			)
			(layer "F.SilkS")
		)
		(fp_line
			(start -0.7874 -0.4064)
			(end 0.7874 -0.4064)
			(stroke
				(width 0.1524)
				(type default)
			)
			(layer "F.SilkS")
		)
		(fp_line
			(start 0.7874 -0.4064)
			(end 0.7874 0.4064)
			(stroke
				(width 0.1524)
				(type default)
			)
			(layer "F.SilkS")
		)
		(fp_line
			(start -0.67945 0.3048)
			(end -0.67945 -0.305054)
			(stroke
				(width 0.1)
				(type default)
			)
			(layer "F.Fab")
		)
		(fp_line
			(start -0.12065 0.3048)
			(end -0.67945 0.3048)
			(stroke
				(width 0.1)
				(type default)
			)
			(layer "F.Fab")
		)
		(fp_line
			(start 0.120396 0.3048)
			(end 0.120396 0.2794)
			(stroke
				(width 0.1)
				(type default)
			)
			(layer "F.Fab")
		)
		(fp_line
			(start 0.67945 0.3048)
			(end 0.120396 0.3048)
			(stroke
				(width 0.1)
				(type default)
			)
			(layer "F.Fab")
		)
		(fp_line
			(start -0.12065 0.2794)
			(end -0.12065 0.3048)
			(stroke
				(width 0.1)
				(type default)
			)
			(layer "F.Fab")
		)
		(fp_line
			(start 0.120396 0.2794)
			(end -0.12065 0.2794)
			(stroke
				(width 0.1)
				(type default)
			)
			(layer "F.Fab")
		)
		(fp_line
			(start -0.12065 -0.2794)
			(end 0.12065 -0.2794)
			(stroke
				(width 0.1)
				(type default)
			)
			(layer "F.Fab")
		)
		(fp_line
			(start 0.12065 -0.2794)
			(end 0.12065 -0.3048)
			(stroke
				(width 0.1)
				(type default)
			)
			(layer "F.Fab")
		)
		(fp_line
			(start 0.12065 -0.3048)
			(end 0.67945 -0.3048)
			(stroke
				(width 0.1)
				(type default)
			)
			(layer "F.Fab")
		)
		(fp_line
			(start 0.67945 -0.3048)
			(end 0.67945 0.3048)
			(stroke
				(width 0.1)
				(type default)
			)
			(layer "F.Fab")
		)
		(fp_line
			(start -0.67945 -0.305054)
			(end -0.12065 -0.305054)
			(stroke
				(width 0.1)
				(type default)
			)
			(layer "F.Fab")
		)
		(fp_line
			(start -0.12065 -0.305054)
			(end -0.12065 -0.2794)
			(stroke
				(width 0.1)
				(type default)
			)
			(layer "F.Fab")
		)
		(pad "1" smd circle
			(at -0.40005 0 270)
			(size 0 0)
			(layers "F.Cu" "F.Mask" "F.Paste")
			(net "PU_TEST")
		)
		(pad "2" smd circle
			(at 0.40005 0 270)
			(size 0 0)
			(layers "F.Cu" "F.Mask" "F.Paste")
			(net "GND")
		)
	)
	(footprint ""
		(layer "F.Cu")
		(at 93.193362 -339.51545 -90)
		(property "Reference" "PC505_P1_6"
			(at 0 0 270)
			(layer "F.SilkS")
			(hide yes)
			(effects
				(font
					(size 1.27 1.27)
				)
			)
		)
		(property "Value" ""
			(at 0 0 270)
			(layer "F.Fab")
			(effects
				(font
					(size 1.27 1.27)
				)
			)
		)
		(duplicate_pad_numbers_are_jumpers no)
		(fp_line
			(start -0.7874 0.4064)
			(end -0.7874 -0.4064)
			(stroke
				(width 0.1524)
				(type default)
			)
			(layer "F.SilkS")
		)
		(fp_line
			(start 0.7874 0.4064)
			(end -0.7874 0.4064)
			(stroke
				(width 0.1524)
				(type default)
			)
			(layer "F.SilkS")
		)
		(fp_line
			(start -0.7874 -0.4064)
			(end 0.7874 -0.4064)
			(stroke
				(width 0.1524)
				(type default)
			)
			(layer "F.SilkS")
		)
		(fp_line
			(start 0.7874 -0.4064)
			(end 0.7874 0.4064)
			(stroke
				(width 0.1524)
				(type default)
			)
			(layer "F.SilkS")
		)
		(fp_line
			(start -0.67945 0.3048)
			(end -0.67945 -0.305054)
			(stroke
				(width 0.1)
				(type default)
			)
			(layer "F.Fab")
		)
		(fp_line
			(start -0.12065 0.3048)
			(end -0.67945 0.3048)
			(stroke
				(width 0.1)
				(type default)
			)
			(layer "F.Fab")
		)
		(fp_line
			(start 0.120396 0.3048)
			(end 0.120396 0.2794)
			(stroke
				(width 0.1)
				(type default)
			)
			(layer "F.Fab")
		)
		(fp_line
			(start 0.67945 0.3048)
			(end 0.120396 0.3048)
			(stroke
				(width 0.1)
				(type default)
			)
			(layer "F.Fab")
		)
		(fp_line
			(start -0.12065 0.2794)
			(end -0.12065 0.3048)
			(stroke
				(width 0.1)
				(type default)
			)
			(layer "F.Fab")
		)
		(fp_line
			(start 0.120396 0.2794)
			(end -0.12065 0.2794)
			(stroke
				(width 0.1)
				(type default)
			)
			(layer "F.Fab")
		)
		(fp_line
			(start -0.12065 -0.2794)
			(end 0.12065 -0.2794)
			(stroke
				(width 0.1)
				(type default)
			)
			(layer "F.Fab")
		)
		(fp_line
			(start 0.12065 -0.2794)
			(end 0.12065 -0.3048)
			(stroke
				(width 0.1)
				(type default)
			)
			(layer "F.Fab")
		)
		(fp_line
			(start 0.12065 -0.3048)
			(end 0.67945 -0.3048)
			(stroke
				(width 0.1)
				(type default)
			)
			(layer "F.Fab")
		)
		(fp_line
			(start 0.67945 -0.3048)
			(end 0.67945 0.3048)
			(stroke
				(width 0.1)
				(type default)
			)
			(layer "F.Fab")
		)
		(fp_line
			(start -0.67945 -0.305054)
			(end -0.12065 -0.305054)
			(stroke
				(width 0.1)
				(type default)
			)
			(layer "F.Fab")
		)
		(fp_line
			(start -0.12065 -0.305054)
			(end -0.12065 -0.2794)
			(stroke
				(width 0.1)
				(type default)
			)
			(layer "F.Fab")
		)
		(pad "1" smd circle
			(at -0.40005 0 270)
			(size 0 0)
			(layers "F.Cu" "F.Mask" "F.Paste")
			(net "SW_P12V_PVCCIN_CPU1_FLT")
		)
		(pad "2" smd circle
			(at 0.40005 0 270)
			(size 0 0)
			(layers "F.Cu" "F.Mask" "F.Paste")
			(net "GND")
		)
	)
	(footprint ""
		(layer "F.Cu")
		(at 307.6956 -28.7528 180)
		(property "Reference" "C2387"
			(at 0 0 180)
			(layer "F.SilkS")
			(hide yes)
			(effects
				(font
					(size 1.27 1.27)
				)
			)
		)
		(property "Value" ""
			(at 0 0 180)
			(layer "F.Fab")
			(effects
				(font
					(size 1.27 1.27)
				)
			)
		)
		(duplicate_pad_numbers_are_jumpers no)
		(fp_line
			(start 0.7874 0.4064)
			(end -0.7874 0.4064)
			(stroke
				(width 0.1524)
				(type default)
			)
			(layer "F.SilkS")
		)
		(fp_line
			(start 0.7874 -0.4064)
			(end 0.7874 0.4064)
			(stroke
				(width 0.1524)
				(type default)
			)
			(layer "F.SilkS")
		)
		(fp_line
			(start -0.7874 0.4064)
			(end -0.7874 -0.4064)
			(stroke
				(width 0.1524)
				(type default)
			)
			(layer "F.SilkS")
		)
		(fp_line
			(start -0.7874 -0.4064)
			(end 0.7874 -0.4064)
			(stroke
				(width 0.1524)
				(type default)
			)
			(layer "F.SilkS")
		)
		(fp_line
			(start 0.67945 0.3048)
			(end 0.120396 0.3048)
			(stroke
				(width 0.1)
				(type default)
			)
			(layer "F.Fab")
		)
		(fp_line
			(start 0.67945 -0.3048)
			(end 0.67945 0.3048)
			(stroke
				(width 0.1)
				(type default)
			)
			(layer "F.Fab")
		)
		(fp_line
			(start 0.12065 -0.2794)
			(end 0.12065 -0.3048)
			(stroke
				(width 0.1)
				(type default)
			)
			(layer "F.Fab")
		)
		(fp_line
			(start 0.12065 -0.3048)
			(end 0.67945 -0.3048)
			(stroke
				(width 0.1)
				(type default)
			)
			(layer "F.Fab")
		)
		(fp_line
			(start 0.120396 0.3048)
			(end 0.120396 0.2794)
			(stroke
				(width 0.1)
				(type default)
			)
			(layer "F.Fab")
		)
		(fp_line
			(start 0.120396 0.2794)
			(end -0.12065 0.2794)
			(stroke
				(width 0.1)
				(type default)
			)
			(layer "F.Fab")
		)
		(fp_line
			(start -0.12065 0.3048)
			(end -0.67945 0.3048)
			(stroke
				(width 0.1)
				(type default)
			)
			(layer "F.Fab")
		)
		(fp_line
			(start -0.12065 0.2794)
			(end -0.12065 0.3048)
			(stroke
				(width 0.1)
				(type default)
			)
			(layer "F.Fab")
		)
		(fp_line
			(start -0.12065 -0.2794)
			(end 0.12065 -0.2794)
			(stroke
				(width 0.1)
				(type default)
			)
			(layer "F.Fab")
		)
		(fp_line
			(start -0.12065 -0.305054)
			(end -0.12065 -0.2794)
			(stroke
				(width 0.1)
				(type default)
			)
			(layer "F.Fab")
		)
		(fp_line
			(start -0.67945 0.3048)
			(end -0.67945 -0.305054)
			(stroke
				(width 0.1)
				(type default)
			)
			(layer "F.Fab")
		)
		(fp_line
			(start -0.67945 -0.305054)
			(end -0.12065 -0.305054)
			(stroke
				(width 0.1)
				(type default)
			)
			(layer "F.Fab")
		)
		(pad "1" smd circle
			(at -0.40005 0 180)
			(size 0 0)
			(layers "F.Cu" "F.Mask" "F.Paste")
			(net "P12V_AUX")
		)
		(pad "2" smd circle
			(at 0.40005 0 180)
			(size 0 0)
			(layers "F.Cu" "F.Mask" "F.Paste")
			(net "GND")
		)
	)
	(footprint ""
		(layer "F.Cu")
		(at 101.380036 -360.929174 -90)
		(property "Reference" "R308"
			(at 0 0 270)
			(layer "F.SilkS")
			(hide yes)
			(effects
				(font
					(size 1.27 1.27)
				)
			)
		)
		(property "Value" ""
			(at 0 0 270)
			(layer "F.Fab")
			(effects
				(font
					(size 1.27 1.27)
				)
			)
		)
		(duplicate_pad_numbers_are_jumpers no)
		(fp_line
			(start -0.7874 0.4064)
			(end -0.7874 -0.4064)
			(stroke
				(width 0.1524)
				(type default)
			)
			(layer "F.SilkS")
		)
		(fp_line
			(start 0.7874 0.4064)
			(end -0.7874 0.4064)
			(stroke
				(width 0.1524)
				(type default)
			)
			(layer "F.SilkS")
		)
		(fp_line
			(start -0.7874 -0.4064)
			(end 0.7874 -0.4064)
			(stroke
				(width 0.1524)
				(type default)
			)
			(layer "F.SilkS")
		)
		(fp_line
			(start 0.7874 -0.4064)
			(end 0.7874 0.4064)
			(stroke
				(width 0.1524)
				(type default)
			)
			(layer "F.SilkS")
		)
		(fp_line
			(start -0.67945 0.3048)
			(end -0.67945 -0.305054)
			(stroke
				(width 0.1)
				(type default)
			)
			(layer "F.Fab")
		)
		(fp_line
			(start -0.12065 0.3048)
			(end -0.67945 0.3048)
			(stroke
				(width 0.1)
				(type default)
			)
			(layer "F.Fab")
		)
		(fp_line
			(start 0.120396 0.3048)
			(end 0.120396 0.2794)
			(stroke
				(width 0.1)
				(type default)
			)
			(layer "F.Fab")
		)
		(fp_line
			(start 0.67945 0.3048)
			(end 0.120396 0.3048)
			(stroke
				(width 0.1)
				(type default)
			)
			(layer "F.Fab")
		)
		(fp_line
			(start -0.12065 0.2794)
			(end -0.12065 0.3048)
			(stroke
				(width 0.1)
				(type default)
			)
			(layer "F.Fab")
		)
		(fp_line
			(start 0.120396 0.2794)
			(end -0.12065 0.2794)
			(stroke
				(width 0.1)
				(type default)
			)
			(layer "F.Fab")
		)
		(fp_line
			(start -0.12065 -0.2794)
			(end 0.12065 -0.2794)
			(stroke
				(width 0.1)
				(type default)
			)
			(layer "F.Fab")
		)
		(fp_line
			(start 0.12065 -0.2794)
			(end 0.12065 -0.3048)
			(stroke
				(width 0.1)
				(type default)
			)
			(layer "F.Fab")
		)
		(fp_line
			(start 0.12065 -0.3048)
			(end 0.67945 -0.3048)
			(stroke
				(width 0.1)
				(type default)
			)
			(layer "F.Fab")
		)
		(fp_line
			(start 0.67945 -0.3048)
			(end 0.67945 0.3048)
			(stroke
				(width 0.1)
				(type default)
			)
			(layer "F.Fab")
		)
		(fp_line
			(start -0.67945 -0.305054)
			(end -0.12065 -0.305054)
			(stroke
				(width 0.1)
				(type default)
			)
			(layer "F.Fab")
		)
		(fp_line
			(start -0.12065 -0.305054)
			(end -0.12065 -0.2794)
			(stroke
				(width 0.1)
				(type default)
			)
			(layer "F.Fab")
		)
		(pad "1" smd circle
			(at -0.40005 0 270)
			(size 0 0)
			(layers "F.Cu" "F.Mask" "F.Paste")
			(net "PWRGD_PVCCIN_CPU1")
		)
		(pad "2" smd circle
			(at 0.40005 0 270)
			(size 0 0)
			(layers "F.Cu" "F.Mask" "F.Paste")
			(net "PWRGD_PVCCIN_CPU1_R")
		)
	)
	(footprint ""
		(layer "F.Cu")
		(at 185.346086 -353.650296 -90)
		(property "Reference" "PC1195_P1_3"
			(at 0 0 270)
			(layer "F.SilkS")
			(hide yes)
			(effects
				(font
					(size 1.27 1.27)
				)
			)
		)
		(property "Value" ""
			(at 0 0 270)
			(layer "F.Fab")
			(effects
				(font
					(size 1.27 1.27)
				)
			)
		)
		(duplicate_pad_numbers_are_jumpers no)
		(fp_line
			(start -0.7874 0.4064)
			(end -0.7874 -0.4064)
			(stroke
				(width 0.1524)
				(type default)
			)
			(layer "F.SilkS")
		)
		(fp_line
			(start 0.7874 0.4064)
			(end -0.7874 0.4064)
			(stroke
				(width 0.1524)
				(type default)
			)
			(layer "F.SilkS")
		)
		(fp_line
			(start -0.7874 -0.4064)
			(end 0.7874 -0.4064)
			(stroke
				(width 0.1524)
				(type default)
			)
			(layer "F.SilkS")
		)
		(fp_line
			(start 0.7874 -0.4064)
			(end 0.7874 0.4064)
			(stroke
				(width 0.1524)
				(type default)
			)
			(layer "F.SilkS")
		)
		(fp_line
			(start -0.67945 0.3048)
			(end -0.67945 -0.305054)
			(stroke
				(width 0.1)
				(type default)
			)
			(layer "F.Fab")
		)
		(fp_line
			(start -0.12065 0.3048)
			(end -0.67945 0.3048)
			(stroke
				(width 0.1)
				(type default)
			)
			(layer "F.Fab")
		)
		(fp_line
			(start 0.120396 0.3048)
			(end 0.120396 0.2794)
			(stroke
				(width 0.1)
				(type default)
			)
			(layer "F.Fab")
		)
		(fp_line
			(start 0.67945 0.3048)
			(end 0.120396 0.3048)
			(stroke
				(width 0.1)
				(type default)
			)
			(layer "F.Fab")
		)
		(fp_line
			(start -0.12065 0.2794)
			(end -0.12065 0.3048)
			(stroke
				(width 0.1)
				(type default)
			)
			(layer "F.Fab")
		)
		(fp_line
			(start 0.120396 0.2794)
			(end -0.12065 0.2794)
			(stroke
				(width 0.1)
				(type default)
			)
			(layer "F.Fab")
		)
		(fp_line
			(start -0.12065 -0.2794)
			(end 0.12065 -0.2794)
			(stroke
				(width 0.1)
				(type default)
			)
			(layer "F.Fab")
		)
		(fp_line
			(start 0.12065 -0.2794)
			(end 0.12065 -0.3048)
			(stroke
				(width 0.1)
				(type default)
			)
			(layer "F.Fab")
		)
		(fp_line
			(start 0.12065 -0.3048)
			(end 0.67945 -0.3048)
			(stroke
				(width 0.1)
				(type default)
			)
			(layer "F.Fab")
		)
		(fp_line
			(start 0.67945 -0.3048)
			(end 0.67945 0.3048)
			(stroke
				(width 0.1)
				(type default)
			)
			(layer "F.Fab")
		)
		(fp_line
			(start -0.67945 -0.305054)
			(end -0.12065 -0.305054)
			(stroke
				(width 0.1)
				(type default)
			)
			(layer "F.Fab")
		)
		(fp_line
			(start -0.12065 -0.305054)
			(end -0.12065 -0.2794)
			(stroke
				(width 0.1)
				(type default)
			)
			(layer "F.Fab")
		)
		(pad "1" smd circle
			(at -0.40005 0 270)
			(size 0 0)
			(layers "F.Cu" "F.Mask" "F.Paste")
			(net "SW_P12V_PVCCFA_EHV_FIVRA_CPU1_R")
		)
		(pad "2" smd circle
			(at 0.40005 0 270)
			(size 0 0)
			(layers "F.Cu" "F.Mask" "F.Paste")
			(net "GND")
		)
	)
)
